FILE_TYPE=LIBRARY_PARTS;

primitive 'CONN3_C95678002','CONN3_C95678002_THLF','CONN3_C95678002_PIP';
  pin
    'IO1':
      PIN_NUMBER='(1)';
      PINUSE='UNSPEC';
      NO_LOAD_CHECK='BOTH';
      NO_IO_CHECK='BOTH';
      ALLOW_CONNECT='TRUE';
    'IO2':
      PIN_NUMBER='(2)';
      PINUSE='UNSPEC';
      NO_LOAD_CHECK='BOTH';
      NO_IO_CHECK='BOTH';
      ALLOW_CONNECT='TRUE';
    'IO3':
      PIN_NUMBER='(3)';
      PINUSE='UNSPEC';
      NO_LOAD_CHECK='BOTH';
      NO_IO_CHECK='BOTH';
      ALLOW_CONNECT='TRUE';
  end_pin;
  body
    PART_NAME='CONN3_C95678002';
    PHYS_DES_PREFIX='J';
  end_body;
end_primitive;
END.
